(kicad_pcb
	(version 20241229)
	(generator "pcbnew")
	(generator_version "9.0")
	(general
		(thickness 1.599998)
		(legacy_teardrops no)
	)
	(paper "A4")
	(title_block
		(date "2023-02-12")
		(rev "1.1.5")
		(comment 9 "footprint 108 of 473 (U3), pads 392-467 of 484")
	)
	(layers
		(0 "F.Cu" signal)
		(4 "In1.Cu" power "In1.GND")
		(6 "In2.Cu" signal)
		(8 "In3.Cu" power "In3.GND")
		(10 "In4.Cu" power "In4.VCC")
		(12 "In5.Cu" signal)
		(14 "In6.Cu" power "In6.VCC")
		(2 "B.Cu" signal)
		(9 "F.Adhes" user "F.Adhesive")
		(11 "B.Adhes" user "B.Adhesive")
		(13 "F.Paste" user)
		(15 "B.Paste" user)
		(5 "F.SilkS" user "F.Silkscreen")
		(7 "B.SilkS" user "B.Silkscreen")
		(1 "F.Mask" user)
		(3 "B.Mask" user)
		(17 "Dwgs.User" user "User.Drawings")
		(19 "Cmts.User" user "User.Comments")
		(21 "Eco1.User" user "User.Eco1")
		(23 "Eco2.User" user "User.Eco2")
		(25 "Edge.Cuts" user)
		(27 "Margin" user)
		(31 "F.CrtYd" user "F.Courtyard")
		(29 "B.CrtYd" user "B.Courtyard")
		(35 "F.Fab" user)
		(33 "B.Fab" user)
	)
	(footprint "antmicro-footprints:BGA-484_23x23mm_Layout22x22_P1mm_FBG484"
		(locked yes)
		(layer "F.Cu")
		(at 169.036328 95.997157 -90)
		(property "Reference" "U3"
			(at -11.8 -12 270)
			(layer "F.SilkS")
			(effects
				(font
					(size 0.7 0.7)
					(thickness 0.15)
				)
				(justify left bottom)
			)
		)
		(property "Value" "XC7K70T-FBG484"
			(at -10.4 0.4 270)
			(layer "F.Fab")
			(effects
				(font
					(size 0.7 0.7)
					(thickness 0.15)
				)
				(justify left bottom)
			)
		)
		(property "Description" "Kintex®-7 Field Programmable Gate Array (FPGA) IC 285 484-BBGA, FCBGA"
			(at 0 0 270)
			(layer "F.Fab")
			(hide yes)
			(effects
				(font
					(size 1.27 1.27)
					(thickness 0.15)
				)
			)
		)
		(property "Author" "Antmicro"
			(at 73.039171 265.033485 0)
			(layer "F.Fab")
			(hide yes)
			(effects
				(font
					(size 1 1)
					(thickness 0.15)
				)
			)
		)
		(property "License" "Apache-2.0"
			(at 73.039171 265.033485 0)
			(layer "F.Fab")
			(hide yes)
			(effects
				(font
					(size 1 1)
					(thickness 0.15)
				)
			)
		)
		(property "MPN" "XC7K70T-1FBG484C"
			(at 73.039171 265.033485 0)
			(layer "F.Fab")
			(hide yes)
			(effects
				(font
					(size 1 1)
					(thickness 0.15)
				)
			)
		)
		(property "Manufacturer" "AMD-Xilinx"
			(at 73.039171 265.033485 0)
			(layer "F.Fab")
			(hide yes)
			(effects
				(font
					(size 1 1)
					(thickness 0.15)
				)
			)
		)
		(sheetname "FPGA Banks")
		(sheetfile "fpga-banks.kicad_sch")
		(attr smd)
		(pad "T18" smd circle
			(at 6.5 4.5 270)
			(size 0.51 0.51)
			(layers "F.Cu" "F.Mask" "F.Paste")
			(net 458 "unconnected-(U3I-IO_L3P_T0_DQS_13-PadT18)")
			(pinfunction "IO_L3P_T0_DQS_13")
			(pintype "bidirectional+no_connect")
		)
		(pad "T19" smd circle
			(at 7.5 4.5 270)
			(size 0.51 0.51)
			(layers "F.Cu" "F.Mask" "F.Paste")
			(net 462 "unconnected-(U3I-IO_0_13-PadT19)")
			(pinfunction "IO_0_13")
			(pintype "bidirectional+no_connect")
		)
		(pad "T20" smd circle
			(at 8.5 4.5 270)
			(size 0.51 0.51)
			(layers "F.Cu" "F.Mask" "F.Paste")
			(net 467 "unconnected-(U3I-IO_L6P_T0_13-PadT20)")
			(pinfunction "IO_L6P_T0_13")
			(pintype "bidirectional+no_connect")
		)
		(pad "T21" smd circle
			(at 9.5 4.5 270)
			(size 0.51 0.51)
			(layers "F.Cu" "F.Mask" "F.Paste")
			(net 471 "unconnected-(U3I-IO_L1P_T0_13-PadT21)")
			(pinfunction "IO_L1P_T0_13")
			(pintype "bidirectional+no_connect")
		)
		(pad "T22" smd circle
			(at 10.5 4.5 270)
			(size 0.51 0.51)
			(layers "F.Cu" "F.Mask" "F.Paste")
			(net 459 "3V3_SYS")
			(pinfunction "VCCO_13")
			(pintype "passive")
		)
		(pad "U1" smd circle
			(at -10.5 5.5 270)
			(size 0.51 0.51)
			(layers "F.Cu" "F.Mask" "F.Paste")
			(net 338 "DQ15_A")
			(pinfunction "IO_L10N_T1_34")
			(pintype "bidirectional")
		)
		(pad "U2" smd circle
			(at -9.5 5.5 270)
			(size 0.51 0.51)
			(layers "F.Cu" "F.Mask" "F.Paste")
			(net 649 "DQ_S1_P")
			(pinfunction "IO_L15P_T2_DQS_34")
			(pintype "bidirectional")
		)
		(pad "U3" smd circle
			(at -8.5 5.5 270)
			(size 0.51 0.51)
			(layers "F.Cu" "F.Mask" "F.Paste")
			(net 404 "IO_U3")
			(pinfunction "IO_L13N_T2_MRCC_34")
			(pintype "bidirectional")
		)
		(pad "U4" smd circle
			(at -7.5 5.5 270)
			(size 0.51 0.51)
			(layers "F.Cu" "F.Mask" "F.Paste")
			(net 5 "GND")
			(pinfunction "GND")
			(pintype "passive")
		)
		(pad "U5" smd circle
			(at -6.5 5.5 270)
			(size 0.51 0.51)
			(layers "F.Cu" "F.Mask" "F.Paste")
			(net 405 "IO_U5")
			(pinfunction "IO_L16N_T2_34")
			(pintype "bidirectional")
		)
		(pad "U6" smd circle
			(at -5.5 5.5 270)
			(size 0.51 0.51)
			(layers "F.Cu" "F.Mask" "F.Paste")
			(net 472 "unconnected-(U3E-IO_L10N_T1_33-PadU6)")
			(pinfunction "IO_L10N_T1_33")
			(pintype "bidirectional+no_connect")
		)
		(pad "U7" smd circle
			(at -4.5 5.5 270)
			(size 0.51 0.51)
			(layers "F.Cu" "F.Mask" "F.Paste")
			(net 473 "unconnected-(U3E-IO_L10P_T1_33-PadU7)")
			(pinfunction "IO_L10P_T1_33")
			(pintype "bidirectional+no_connect")
		)
		(pad "U8" smd circle
			(at -3.5 5.5 270)
			(size 0.51 0.51)
			(layers "F.Cu" "F.Mask" "F.Paste")
			(net 474 "unconnected-(U3E-IO_L9P_T1_DQS_33-PadU8)")
			(pinfunction "IO_L9P_T1_DQS_33")
			(pintype "bidirectional+no_connect")
		)
		(pad "U9" smd circle
			(at -2.5 5.5 270)
			(size 0.51 0.51)
			(layers "F.Cu" "F.Mask" "F.Paste")
			(net 66 "VDDQ")
			(pinfunction "VCCO_33")
			(pintype "passive")
		)
		(pad "U10" smd circle
			(at -1.5 5.5 270)
			(size 0.51 0.51)
			(layers "F.Cu" "F.Mask" "F.Paste")
			(net 475 "unconnected-(U3E-IO_L14P_T2_SRCC_33-PadU10)")
			(pinfunction "IO_L14P_T2_SRCC_33")
			(pintype "bidirectional+no_connect")
		)
		(pad "U11" smd circle
			(at -0.5 5.5 270)
			(size 0.51 0.51)
			(layers "F.Cu" "F.Mask" "F.Paste")
			(net 476 "unconnected-(U3E-IO_L17N_T2_33-PadU11)")
			(pinfunction "IO_L17N_T2_33")
			(pintype "bidirectional+no_connect")
		)
		(pad "U12" smd circle
			(at 0.5 5.5 270)
			(size 0.51 0.51)
			(layers "F.Cu" "F.Mask" "F.Paste")
			(net 487 "IO_U12")
			(pinfunction "IO_L17P_T2_33")
			(pintype "bidirectional")
		)
		(pad "U13" smd circle
			(at 1.5 5.5 270)
			(size 0.51 0.51)
			(layers "F.Cu" "F.Mask" "F.Paste")
			(net 477 "unconnected-(U3E-IO_L24N_T3_33-PadU13)")
			(pinfunction "IO_L24N_T3_33")
			(pintype "bidirectional+no_connect")
		)
		(pad "U14" smd circle
			(at 2.5 5.5 270)
			(size 0.51 0.51)
			(layers "F.Cu" "F.Mask" "F.Paste")
			(net 5 "GND")
			(pinfunction "GND")
			(pintype "passive")
		)
		(pad "U15" smd circle
			(at 3.5 5.5 270)
			(size 0.51 0.51)
			(layers "F.Cu" "F.Mask" "F.Paste")
			(net 478 "unconnected-(U3I-IO_L24N_T3_13-PadU15)")
			(pinfunction "IO_L24N_T3_13")
			(pintype "bidirectional+no_connect")
		)
		(pad "U16" smd circle
			(at 4.5 5.5 270)
			(size 0.51 0.51)
			(layers "F.Cu" "F.Mask" "F.Paste")
			(net 501 "unconnected-(U3I-IO_L19P_T3_13-PadU16)")
			(pinfunction "IO_L19P_T3_13")
			(pintype "bidirectional+no_connect")
		)
		(pad "U17" smd circle
			(at 5.5 5.5 270)
			(size 0.51 0.51)
			(layers "F.Cu" "F.Mask" "F.Paste")
			(net 502 "unconnected-(U3I-IO_L5P_T0_13-PadU17)")
			(pinfunction "IO_L5P_T0_13")
			(pintype "bidirectional+no_connect")
		)
		(pad "U18" smd circle
			(at 6.5 5.5 270)
			(size 0.51 0.51)
			(layers "F.Cu" "F.Mask" "F.Paste")
			(net 503 "unconnected-(U3I-IO_L3N_T0_DQS_13-PadU18)")
			(pinfunction "IO_L3N_T0_DQS_13")
			(pintype "bidirectional+no_connect")
		)
		(pad "U19" smd circle
			(at 7.5 5.5 270)
			(size 0.51 0.51)
			(layers "F.Cu" "F.Mask" "F.Paste")
			(net 459 "3V3_SYS")
			(pinfunction "VCCO_13")
			(pintype "passive")
		)
		(pad "U20" smd circle
			(at 8.5 5.5 270)
			(size 0.51 0.51)
			(layers "F.Cu" "F.Mask" "F.Paste")
			(net 504 "unconnected-(U3I-IO_L6N_T0_VREF_13-PadU20)")
			(pinfunction "IO_L6N_T0_VREF_13")
			(pintype "bidirectional+no_connect")
		)
		(pad "U21" smd circle
			(at 9.5 5.5 270)
			(size 0.51 0.51)
			(layers "F.Cu" "F.Mask" "F.Paste")
			(net 505 "unconnected-(U3I-IO_L1N_T0_13-PadU21)")
			(pinfunction "IO_L1N_T0_13")
			(pintype "bidirectional+no_connect")
		)
		(pad "U22" smd circle
			(at 10.5 5.5 270)
			(size 0.51 0.51)
			(layers "F.Cu" "F.Mask" "F.Paste")
			(net 506 "unconnected-(U3I-IO_L2P_T0_13-PadU22)")
			(pinfunction "IO_L2P_T0_13")
			(pintype "bidirectional+no_connect")
		)
		(pad "V1" smd circle
			(at -10.5 6.5 270)
			(size 0.51 0.51)
			(layers "F.Cu" "F.Mask" "F.Paste")
			(net 5 "GND")
			(pinfunction "GND")
			(pintype "passive")
		)
		(pad "V2" smd circle
			(at -9.5 6.5 270)
			(size 0.51 0.51)
			(layers "F.Cu" "F.Mask" "F.Paste")
			(net 648 "DQ_S1_N")
			(pinfunction "IO_L15N_T2_DQS_34")
			(pintype "bidirectional")
		)
		(pad "V3" smd circle
			(at -8.5 6.5 270)
			(size 0.51 0.51)
			(layers "F.Cu" "F.Mask" "F.Paste")
			(net 403 "IO_V3")
			(pinfunction "IO_L17P_T2_34")
			(pintype "bidirectional")
		)
		(pad "V4" smd circle
			(at -7.5 6.5 270)
			(size 0.51 0.51)
			(layers "F.Cu" "F.Mask" "F.Paste")
			(net 399 "IO_V4")
			(pinfunction "IO_L14P_T2_SRCC_34")
			(pintype "bidirectional")
		)
		(pad "V5" smd circle
			(at -6.5 6.5 270)
			(size 0.51 0.51)
			(layers "F.Cu" "F.Mask" "F.Paste")
			(net 512 "VRP")
			(pinfunction "IO_25_VRP_34")
			(pintype "bidirectional")
		)
		(pad "V6" smd circle
			(at -5.5 6.5 270)
			(size 0.51 0.51)
			(layers "F.Cu" "F.Mask" "F.Paste")
			(net 66 "VDDQ")
			(pinfunction "VCCO_33")
			(pintype "passive")
		)
		(pad "V7" smd circle
			(at -4.5 6.5 270)
			(size 0.51 0.51)
			(layers "F.Cu" "F.Mask" "F.Paste")
			(net 507 "unconnected-(U3E-IO_L11P_T1_SRCC_33-PadV7)")
			(pinfunction "IO_L11P_T1_SRCC_33")
			(pintype "bidirectional+no_connect")
		)
		(pad "V8" smd circle
			(at -3.5 6.5 270)
			(size 0.51 0.51)
			(layers "F.Cu" "F.Mask" "F.Paste")
			(net 508 "unconnected-(U3E-IO_L9N_T1_DQS_33-PadV8)")
			(pinfunction "IO_L9N_T1_DQS_33")
			(pintype "bidirectional+no_connect")
		)
		(pad "V9" smd circle
			(at -2.5 6.5 270)
			(size 0.51 0.51)
			(layers "F.Cu" "F.Mask" "F.Paste")
			(net 509 "unconnected-(U3E-IO_L14N_T2_SRCC_33-PadV9)")
			(pinfunction "IO_L14N_T2_SRCC_33")
			(pintype "bidirectional+no_connect")
		)
		(pad "V10" smd circle
			(at -1.5 6.5 270)
			(size 0.51 0.51)
			(layers "F.Cu" "F.Mask" "F.Paste")
			(net 513 "unconnected-(U3E-IO_L15P_T2_DQS_33-PadV10)")
			(pinfunction "IO_L15P_T2_DQS_33")
			(pintype "bidirectional+no_connect")
		)
		(pad "V11" smd circle
			(at -0.5 6.5 270)
			(size 0.51 0.51)
			(layers "F.Cu" "F.Mask" "F.Paste")
			(net 5 "GND")
			(pinfunction "GND")
			(pintype "passive")
		)
		(pad "V12" smd circle
			(at 0.5 6.5 270)
			(size 0.51 0.51)
			(layers "F.Cu" "F.Mask" "F.Paste")
			(net 486 "IO_V12")
			(pinfunction "IO_L23N_T3_33")
			(pintype "bidirectional")
		)
		(pad "V13" smd circle
			(at 1.5 6.5 270)
			(size 0.51 0.51)
			(layers "F.Cu" "F.Mask" "F.Paste")
			(net 515 "unconnected-(U3E-IO_L23P_T3_33-PadV13)")
			(pinfunction "IO_L23P_T3_33")
			(pintype "bidirectional+no_connect")
		)
		(pad "V14" smd circle
			(at 2.5 6.5 270)
			(size 0.51 0.51)
			(layers "F.Cu" "F.Mask" "F.Paste")
			(net 516 "unconnected-(U3I-IO_25_13-PadV14)")
			(pinfunction "IO_25_13")
			(pintype "bidirectional+no_connect")
		)
		(pad "V15" smd circle
			(at 3.5 6.5 270)
			(size 0.51 0.51)
			(layers "F.Cu" "F.Mask" "F.Paste")
			(net 494 "HR_DQ5")
			(pinfunction "IO_L23P_T3_13")
			(pintype "bidirectional")
		)
		(pad "V16" smd circle
			(at 4.5 6.5 270)
			(size 0.51 0.51)
			(layers "F.Cu" "F.Mask" "F.Paste")
			(net 459 "3V3_SYS")
			(pinfunction "VCCO_13")
			(pintype "passive")
		)
		(pad "V17" smd circle
			(at 5.5 6.5 270)
			(size 0.51 0.51)
			(layers "F.Cu" "F.Mask" "F.Paste")
			(net 488 "HR_RST")
			(pinfunction "IO_L19N_T3_VREF_13")
			(pintype "bidirectional")
		)
		(pad "V18" smd circle
			(at 6.5 6.5 270)
			(size 0.51 0.51)
			(layers "F.Cu" "F.Mask" "F.Paste")
			(net 517 "unconnected-(U3I-IO_L5N_T0_13-PadV18)")
			(pinfunction "IO_L5N_T0_13")
			(pintype "bidirectional+no_connect")
		)
		(pad "V19" smd circle
			(at 7.5 6.5 270)
			(size 0.51 0.51)
			(layers "F.Cu" "F.Mask" "F.Paste")
			(net 518 "unconnected-(U3I-IO_L12P_T1_MRCC_13-PadV19)")
			(pinfunction "IO_L12P_T1_MRCC_13")
			(pintype "bidirectional+no_connect")
		)
		(pad "V20" smd circle
			(at 8.5 6.5 270)
			(size 0.51 0.51)
			(layers "F.Cu" "F.Mask" "F.Paste")
			(net 528 "unconnected-(U3I-IO_L11P_T1_SRCC_13-PadV20)")
			(pinfunction "IO_L11P_T1_SRCC_13")
			(pintype "bidirectional+no_connect")
		)
		(pad "V21" smd circle
			(at 9.5 6.5 270)
			(size 0.51 0.51)
			(layers "F.Cu" "F.Mask" "F.Paste")
			(net 5 "GND")
			(pinfunction "GND")
			(pintype "passive")
		)
		(pad "V22" smd circle
			(at 10.5 6.5 270)
			(size 0.51 0.51)
			(layers "F.Cu" "F.Mask" "F.Paste")
			(net 532 "unconnected-(U3I-IO_L2N_T0_13-PadV22)")
			(pinfunction "IO_L2N_T0_13")
			(pintype "bidirectional+no_connect")
		)
		(pad "W1" smd circle
			(at -10.5 7.5 270)
			(size 0.51 0.51)
			(layers "F.Cu" "F.Mask" "F.Paste")
			(net 336 "DMI_1A")
			(pinfunction "IO_L20P_T3_34")
			(pintype "bidirectional")
		)
		(pad "W2" smd circle
			(at -9.5 7.5 270)
			(size 0.51 0.51)
			(layers "F.Cu" "F.Mask" "F.Paste")
			(net 335 "DQ08_A")
			(pinfunction "IO_L17N_T2_34")
			(pintype "bidirectional")
		)
		(pad "W3" smd circle
			(at -8.5 7.5 270)
			(size 0.51 0.51)
			(layers "F.Cu" "F.Mask" "F.Paste")
			(net 66 "VDDQ")
			(pinfunction "VCCO_34")
			(pintype "passive")
		)
		(pad "W4" smd circle
			(at -7.5 7.5 270)
			(size 0.51 0.51)
			(layers "F.Cu" "F.Mask" "F.Paste")
			(net 398 "IO_W4")
			(pinfunction "IO_L14N_T2_SRCC_34")
			(pintype "bidirectional")
		)
		(pad "W5" smd circle
			(at -6.5 7.5 270)
			(size 0.51 0.51)
			(layers "F.Cu" "F.Mask" "F.Paste")
			(net 533 "unconnected-(U3D-IO_L19P_T3_34-PadW5)")
			(pinfunction "IO_L19P_T3_34")
			(pintype "bidirectional+no_connect")
		)
		(pad "W6" smd circle
			(at -5.5 7.5 270)
			(size 0.51 0.51)
			(layers "F.Cu" "F.Mask" "F.Paste")
			(net 534 "unconnected-(U3E-IO_L7P_T1_33-PadW6)")
			(pinfunction "IO_L7P_T1_33")
			(pintype "bidirectional+no_connect")
		)
		(pad "W7" smd circle
			(at -4.5 7.5 270)
			(size 0.51 0.51)
			(layers "F.Cu" "F.Mask" "F.Paste")
			(net 535 "unconnected-(U3E-IO_L11N_T1_SRCC_33-PadW7)")
			(pinfunction "IO_L11N_T1_SRCC_33")
			(pintype "bidirectional+no_connect")
		)
		(pad "W8" smd circle
			(at -3.5 7.5 270)
			(size 0.51 0.51)
			(layers "F.Cu" "F.Mask" "F.Paste")
			(net 5 "GND")
			(pinfunction "GND")
			(pintype "passive")
		)
		(pad "W9" smd circle
			(at -2.5 7.5 270)
			(size 0.51 0.51)
			(layers "F.Cu" "F.Mask" "F.Paste")
			(net 536 "unconnected-(U3E-IO_L13P_T2_MRCC_33-PadW9)")
			(pinfunction "IO_L13P_T2_MRCC_33")
			(pintype "bidirectional+no_connect")
		)
		(pad "W10" smd circle
			(at -1.5 7.5 270)
			(size 0.51 0.51)
			(layers "F.Cu" "F.Mask" "F.Paste")
			(net 537 "unconnected-(U3E-IO_L15N_T2_DQS_33-PadW10)")
			(pinfunction "IO_L15N_T2_DQS_33")
			(pintype "bidirectional+no_connect")
		)
		(pad "W11" smd circle
			(at -0.5 7.5 270)
			(size 0.51 0.51)
			(layers "F.Cu" "F.Mask" "F.Paste")
			(net 483 "IO_W11")
			(pinfunction "IO_L6P_T0_33")
			(pintype "bidirectional")
		)
		(pad "W12" smd circle
			(at 0.5 7.5 270)
			(size 0.51 0.51)
			(layers "F.Cu" "F.Mask" "F.Paste")
			(net 485 "IO_W12")
			(pinfunction "IO_L19P_T3_33")
			(pintype "bidirectional")
		)
		(pad "W13" smd circle
			(at 1.5 7.5 270)
			(size 0.51 0.51)
			(layers "F.Cu" "F.Mask" "F.Paste")
			(net 66 "VDDQ")
			(pinfunction "VCCO_33")
			(pintype "passive")
		)
		(pad "W14" smd circle
			(at 2.5 7.5 270)
			(size 0.51 0.51)
			(layers "F.Cu" "F.Mask" "F.Paste")
			(net 499 "HR_DQ3")
			(pinfunction "IO_L22P_T3_13")
			(pintype "bidirectional")
		)
		(pad "W15" smd circle
			(at 3.5 7.5 270)
			(size 0.51 0.51)
			(layers "F.Cu" "F.Mask" "F.Paste")
			(net 491 "HR_DQ0")
			(pinfunction "IO_L23N_T3_13")
			(pintype "bidirectional")
		)
		(pad "W16" smd circle
			(at 4.5 7.5 270)
			(size 0.51 0.51)
			(layers "F.Cu" "F.Mask" "F.Paste")
			(net 538 "unconnected-(U3I-IO_L21P_T3_DQS_13-PadW16)")
			(pinfunction "IO_L21P_T3_DQS_13")
			(pintype "bidirectional+no_connect")
		)
		(pad "W17" smd circle
			(at 5.5 7.5 270)
			(size 0.51 0.51)
			(layers "F.Cu" "F.Mask" "F.Paste")
			(net 496 "HR_DQ7")
			(pinfunction "IO_L14P_T2_SRCC_13")
			(pintype "bidirectional")
		)
		(pad "W18" smd circle
			(at 6.5 7.5 270)
			(size 0.51 0.51)
			(layers "F.Cu" "F.Mask" "F.Paste")
			(net 5 "GND")
			(pinfunction "GND")
			(pintype "passive")
		)
		(pad "W19" smd circle
			(at 7.5 7.5 270)
			(size 0.51 0.51)
			(layers "F.Cu" "F.Mask" "F.Paste")
			(net 539 "unconnected-(U3I-IO_L12N_T1_MRCC_13-PadW19)")
			(pinfunction "IO_L12N_T1_MRCC_13")
			(pintype "bidirectional+no_connect")
		)
		(pad "W20" smd circle
			(at 8.5 7.5 270)
			(size 0.51 0.51)
			(layers "F.Cu" "F.Mask" "F.Paste")
			(net 444 "AUX_JTAG_TDI")
			(pinfunction "IO_L11N_T1_SRCC_13")
			(pintype "bidirectional")
		)
		(pad "W21" smd circle
			(at 9.5 7.5 270)
			(size 0.51 0.51)
			(layers "F.Cu" "F.Mask" "F.Paste")
			(net 464 "AUX_JTAG_TDO")
			(pinfunction "IO_L4P_T0_13")
			(pintype "bidirectional")
		)
		(pad "W22" smd circle
			(at 10.5 7.5 270)
			(size 0.51 0.51)
			(layers "F.Cu" "F.Mask" "F.Paste")
			(net 442 "AUX_JTAG_TCK")
			(pinfunction "IO_L4N_T0_13")
			(pintype "bidirectional")
		)
		(pad "Y1" smd circle
			(at -10.5 8.5 270)
			(size 0.51 0.51)
			(layers "F.Cu" "F.Mask" "F.Paste")
			(net 334 "DQ09_A")
			(pinfunction "IO_L20N_T3_34")
			(pintype "bidirectional")
		)
		(pad "Y2" smd circle
			(at -9.5 8.5 270)
			(size 0.51 0.51)
			(layers "F.Cu" "F.Mask" "F.Paste")
			(net 352 "CK_A_N")
			(pinfunction "IO_L21N_T3_DQS_34")
			(pintype "bidirectional")
		)
		(pad "Y3" smd circle
			(at -8.5 8.5 270)
			(size 0.51 0.51)
			(layers "F.Cu" "F.Mask" "F.Paste")
			(net 353 "CK_A_P")
			(pinfunction "IO_L21P_T3_DQS_34")
			(pintype "bidirectional")
		)
		(pad "Y4" smd circle
			(at -7.5 8.5 270)
			(size 0.51 0.51)
			(layers "F.Cu" "F.Mask" "F.Paste")
			(net 510 "VREF_34")
			(pinfunction "IO_L19N_T3_VREF_34")
			(pintype "bidirectional")
		)
		(pad "Y5" smd circle
			(at -6.5 8.5 270)
			(size 0.51 0.51)
			(layers "F.Cu" "F.Mask" "F.Paste")
			(net 5 "GND")
			(pinfunction "GND")
			(pintype "passive")
		)
	)
)
